(kicad_pcb
	(version 20260206)
	(generator "pcbnew")
	(generator_version "10.0")
	(general
		(thickness 1.6)
		(legacy_teardrops no)
	)
	(paper "A4")
	(title_block
		(title "panther-plus-userver — 13130-1b_20150205.brd")
		(comment 1 "Honey Badger (Wiwynn) / footprints 215-221 of 1509")
	)
	(layers
		(0 "F.Cu" signal "TOP")
		(4 "In1.Cu" signal "L2")
		(6 "In2.Cu" signal "L3")
		(8 "In3.Cu" signal "L4")
		(10 "In4.Cu" signal "L5")
		(12 "In5.Cu" signal "L6")
		(14 "In6.Cu" signal "L7")
		(16 "In7.Cu" signal "L8")
		(18 "In8.Cu" signal "L9")
		(20 "In9.Cu" signal "L10")
		(22 "In10.Cu" signal "L11")
		(2 "B.Cu" signal "BOTTOM")
		(9 "F.Adhes" user "F.Adhesive")
		(11 "B.Adhes" user "B.Adhesive")
		(13 "F.Paste" user "Package Geometry/Pastemask Top")
		(15 "B.Paste" user "Package Geometry/Pastemask Bottom")
		(5 "F.SilkS" user "Ref Des/Silkscreen Top")
		(7 "B.SilkS" user "Ref Des/Silkscreen Bottom")
		(1 "F.Mask" user "Board Geometry/Soldermask Top")
		(3 "B.Mask" user "Board Geometry/Soldermask Bottom")
		(17 "Dwgs.User" user "User.Drawings")
		(19 "Cmts.User" user "User.Comments")
		(21 "Eco1.User" user "User.Eco1")
		(23 "Eco2.User" user "User.Eco2")
		(25 "Edge.Cuts" user "Board Geometry/Outline")
		(27 "Margin" user)
		(31 "F.CrtYd" user "Package Geometry/Place Bound Top")
		(29 "B.CrtYd" user "Package Geometry/Place Bound Bottom")
		(35 "F.Fab" user "Ref Des/Assembly Top")
		(33 "B.Fab" user "Ref Des/Assembly Bottom")
	)
	(footprint ""
		(layer "F.Cu")
		(at 159.639 -33.782 90)
		(property "Reference" "R148"
			(at 0 0 90)
			(layer "F.SilkS")
			(hide yes)
			(effects
				(font
					(size 1.27 1.27)
				)
			)
		)
		(property "Value" "300R2F-GP"
			(at 0.064008 -3.993896 90)
			(unlocked yes)
			(layer "F.Fab")
			(hide yes)
			(effects
				(font
					(size 1.016 1.016)
					(thickness 0.1524)
				)
			)
		)
		(property "Device Type" "R402H16"
			(at 0.064008 -5.517896 90)
			(unlocked yes)
			(layer "F.Fab")
			(hide yes)
			(effects
				(font
					(size 1.016 1.016)
					(thickness 0.1524)
				)
			)
		)
		(duplicate_pad_numbers_are_jumpers no)
		(fp_rect
			(start -0.381 0.8382)
			(end 0.381 -0.8382)
			(stroke
				(width 0)
				(type default)
			)
			(fill no)
			(layer "F.CrtYd")
		)
		(fp_rect
			(start -0.381 0.8382)
			(end 0.381 -0.8382)
			(stroke
				(width 0)
				(type default)
			)
			(fill no)
			(layer "F.Fab")
		)
		(pad "1" smd custom
			(at 0 -0.4318 90)
			(size 0.127 0.127)
			(layers "F.Cu" "F.Mask" "F.Paste")
			(net "HEARTBEAT_R_LED")
			(options
				(clearance outline)
				(anchor circle)
			)
			(primitives
				(gr_poly
					(pts
						(arc
							(start -0.2032 -0.2794)
							(mid -0.239121 -0.264521)
							(end -0.254 -0.2286)
						)
						(arc
							(start -0.254 0.2286)
							(mid -0.239121 0.264521)
							(end -0.2032 0.2794)
						)
						(arc
							(start 0.2032 0.2794)
							(mid 0.239121 0.264521)
							(end 0.254 0.2286)
						)
						(arc
							(start 0.254 -0.2286)
							(mid 0.239121 -0.264521)
							(end 0.2032 -0.2794)
						)
					)
					(width 0)
					(fill yes)
				)
			)
		)
		(pad "2" smd custom
			(at 0 0.4318 90)
			(size 0.127 0.127)
			(layers "F.Cu" "F.Mask" "F.Paste")
			(net "P3V3_STBY")
			(options
				(clearance outline)
				(anchor circle)
			)
			(primitives
				(gr_poly
					(pts
						(arc
							(start -0.2032 -0.2794)
							(mid -0.239121 -0.264521)
							(end -0.254 -0.2286)
						)
						(arc
							(start -0.254 0.2286)
							(mid -0.239121 0.264521)
							(end -0.2032 0.2794)
						)
						(arc
							(start 0.2032 0.2794)
							(mid 0.239121 0.264521)
							(end 0.254 0.2286)
						)
						(arc
							(start 0.254 -0.2286)
							(mid 0.239121 -0.264521)
							(end 0.2032 -0.2794)
						)
					)
					(width 0)
					(fill yes)
				)
			)
		)
	)
	(footprint ""
		(layer "F.Cu")
		(at 189.865 -16.129 180)
		(property "Reference" "C290"
			(at 0 0 180)
			(layer "F.SilkS")
			(hide yes)
			(effects
				(font
					(size 1.27 1.27)
				)
			)
		)
		(property "Value" "SC10U6D3V3MX-GP"
			(at 0 -2.8194 180)
			(unlocked yes)
			(layer "F.Fab")
			(hide yes)
			(effects
				(font
					(size 1.016 1.016)
					(thickness 0.1524)
				)
			)
		)
		(property "Device Type" "C603H38"
			(at 0 -4.3434 180)
			(unlocked yes)
			(layer "F.Fab")
			(hide yes)
			(effects
				(font
					(size 1.016 1.016)
					(thickness 0.1524)
				)
			)
		)
		(duplicate_pad_numbers_are_jumpers no)
		(fp_line
			(start -0.4064 0)
			(end 0.4064 0)
			(stroke
				(width 0.2286)
				(type default)
			)
			(layer "F.SilkS")
		)
		(fp_rect
			(start -0.635 1.1811)
			(end 0.635 -1.1811)
			(stroke
				(width 0)
				(type default)
			)
			(fill no)
			(layer "F.CrtYd")
		)
		(fp_rect
			(start -0.635 1.1811)
			(end 0.635 -1.1811)
			(stroke
				(width 0)
				(type default)
			)
			(fill no)
			(layer "F.Fab")
		)
		(pad "1" smd custom
			(at 0 -0.6604 180)
			(size 0.19685 0.19685)
			(layers "F.Cu" "F.Mask" "F.Paste")
			(net "PV_VTT_DDR_B")
			(options
				(clearance outline)
				(anchor circle)
			)
			(primitives
				(gr_poly
					(pts
						(arc
							(start 0.508 -0.2921)
							(mid 0.478242 -0.363942)
							(end 0.4064 -0.3937)
						)
						(arc
							(start -0.4064 -0.3937)
							(mid -0.478242 -0.363942)
							(end -0.508 -0.2921)
						)
						(arc
							(start -0.508 0.2921)
							(mid -0.478242 0.363942)
							(end -0.4064 0.3937)
						)
						(arc
							(start 0.4064 0.3937)
							(mid 0.478242 0.363942)
							(end 0.508 0.2921)
						)
					)
					(width 0)
					(fill yes)
				)
			)
		)
		(pad "2" smd custom
			(at 0 0.6604 180)
			(size 0.19685 0.19685)
			(layers "F.Cu" "F.Mask" "F.Paste")
			(net "GND")
			(options
				(clearance outline)
				(anchor circle)
			)
			(primitives
				(gr_poly
					(pts
						(arc
							(start 0.508 -0.2921)
							(mid 0.478242 -0.363942)
							(end 0.4064 -0.3937)
						)
						(arc
							(start -0.4064 -0.3937)
							(mid -0.478242 -0.363942)
							(end -0.508 -0.2921)
						)
						(arc
							(start -0.508 0.2921)
							(mid -0.478242 0.363942)
							(end -0.4064 0.3937)
						)
						(arc
							(start 0.4064 0.3937)
							(mid 0.478242 0.363942)
							(end 0.508 0.2921)
						)
					)
					(width 0)
					(fill yes)
				)
			)
		)
	)
	(footprint ""
		(layer "F.Cu")
		(at 45.7454 -30.4546 -90)
		(property "Reference" "U43"
			(at 0 0 270)
			(layer "F.SilkS")
			(hide yes)
			(effects
				(font
					(size 1.27 1.27)
				)
			)
		)
		(property "Value" "SN74LVC1G11DCKR-GP"
			(at -4.897374 3.525266 270)
			(unlocked yes)
			(layer "F.Fab")
			(hide yes)
			(effects
				(font
					(size 1.016 1.016)
					(thickness 0.1524)
				)
			)
		)
		(property "Device Type" "UMT6H44"
			(at -4.897374 2.001266 270)
			(unlocked yes)
			(layer "F.Fab")
			(hide yes)
			(effects
				(font
					(size 1.016 1.016)
					(thickness 0.1524)
				)
			)
		)
		(duplicate_pad_numbers_are_jumpers no)
		(fp_line
			(start -1.0033 0.3556)
			(end 1.0033 0.3556)
			(stroke
				(width 0.1524)
				(type default)
			)
			(layer "F.SilkS")
		)
		(fp_line
			(start 1.0033 0.3556)
			(end 1.0033 -0.3556)
			(stroke
				(width 0.1524)
				(type default)
			)
			(layer "F.SilkS")
		)
		(fp_line
			(start -1.1557 0.2921)
			(end -1.1557 1.2954)
			(stroke
				(width 0.254)
				(type default)
			)
			(layer "F.SilkS")
		)
		(fp_line
			(start -1.0033 -0.3556)
			(end -1.0033 0.3556)
			(stroke
				(width 0.1524)
				(type default)
			)
			(layer "F.SilkS")
		)
		(fp_line
			(start 1.0033 -0.3556)
			(end -1.0033 -0.3556)
			(stroke
				(width 0.1524)
				(type default)
			)
			(layer "F.SilkS")
		)
		(fp_poly
			(pts
				(xy -1.016 0.3556) (xy 1.016 0.3556) (xy 1.016 -0.3556) (xy -1.016 -0.3556)
			)
			(stroke
				(width 0)
				(type default)
			)
			(fill yes)
			(layer "F.SilkS")
		)
		(fp_poly
			(pts
				(xy -1.0033 -0.8763) (xy -1.2573 -0.8763) (xy -1.2573 0.8763) (xy -0.9906 0.8763) (xy -0.9906 1.4097)
				(xy 0.9906 1.4097) (xy 0.9906 0.8763) (xy 1.2573 0.8763) (xy 1.2573 -0.8763) (xy 0.9906 -0.8763)
				(xy 0.9906 -1.4097) (xy -0.9906 -1.4097) (xy -0.9906 -0.8763)
			)
			(stroke
				(width 0)
				(type default)
			)
			(fill no)
			(layer "F.CrtYd")
		)
		(fp_poly
			(pts
				(xy -1.0033 -0.8763) (xy -1.2573 -0.8763) (xy -1.2573 0.8763) (xy -1.0033 0.8763) (xy -0.9906 0.8763)
				(xy -0.9906 1.4097) (xy 0.9906 1.4097) (xy 0.9906 0.8763) (xy 1.0033 0.8763) (xy 1.2573 0.8763)
				(xy 1.2573 -0.8763) (xy 1.0033 -0.8763) (xy 0.9906 -0.8763) (xy 0.9906 -1.4097) (xy -0.9906 -1.4097)
				(xy -0.9906 -0.8763)
			)
			(stroke
				(width 0)
				(type default)
			)
			(fill no)
			(layer "F.Fab")
		)
		(pad "1" smd rect
			(at -0.65024 0.94996 270)
			(size 0.4064 0.6604)
			(layers "F.Cu" "F.Mask" "F.Paste")
			(net "BMC_PWRBTN#")
		)
		(pad "2" smd rect
			(at 0 0.94996 270)
			(size 0.4064 0.6604)
			(layers "F.Cu" "F.Mask" "F.Paste")
			(net "GND")
		)
		(pad "3" smd rect
			(at 0.65024 0.94996 270)
			(size 0.4064 0.6604)
			(layers "F.Cu" "F.Mask" "F.Paste")
			(net "FPGA_PWRBTN#")
		)
		(pad "4" smd rect
			(at 0.65024 -0.94996 270)
			(size 0.4064 0.6604)
			(layers "F.Cu" "F.Mask" "F.Paste")
			(net "PMU_PWRBTN_R#")
		)
		(pad "5" smd rect
			(at 0 -0.94996 270)
			(size 0.4064 0.6604)
			(layers "F.Cu" "F.Mask" "F.Paste")
			(net "P3V3_CPU")
		)
		(pad "6" smd rect
			(at -0.65024 -0.94996 270)
			(size 0.4064 0.6604)
			(layers "F.Cu" "F.Mask" "F.Paste")
			(net "XDP_PWRBTN#")
		)
	)
	(footprint ""
		(layer "F.Cu")
		(at 59.817 -17.78 90)
		(property "Reference" "R174"
			(at 0 0 90)
			(layer "F.SilkS")
			(hide yes)
			(effects
				(font
					(size 1.27 1.27)
				)
			)
		)
		(property "Value" "0R2J-2-GP"
			(at 0.064008 -3.993896 90)
			(unlocked yes)
			(layer "F.Fab")
			(hide yes)
			(effects
				(font
					(size 1.016 1.016)
					(thickness 0.1524)
				)
			)
		)
		(property "Device Type" "R402H16"
			(at 0.064008 -5.517896 90)
			(unlocked yes)
			(layer "F.Fab")
			(hide yes)
			(effects
				(font
					(size 1.016 1.016)
					(thickness 0.1524)
				)
			)
		)
		(duplicate_pad_numbers_are_jumpers no)
		(fp_rect
			(start -0.381 0.8382)
			(end 0.381 -0.8382)
			(stroke
				(width 0)
				(type default)
			)
			(fill no)
			(layer "F.CrtYd")
		)
		(fp_rect
			(start -0.381 0.8382)
			(end 0.381 -0.8382)
			(stroke
				(width 0)
				(type default)
			)
			(fill no)
			(layer "F.Fab")
		)
		(pad "1" smd custom
			(at 0 -0.4318 90)
			(size 0.127 0.127)
			(layers "F.Cu" "F.Mask" "F.Paste")
			(net "SPI_CLK_GBE_R")
			(options
				(clearance outline)
				(anchor circle)
			)
			(primitives
				(gr_poly
					(pts
						(arc
							(start -0.2032 -0.2794)
							(mid -0.239121 -0.264521)
							(end -0.254 -0.2286)
						)
						(arc
							(start -0.254 0.2286)
							(mid -0.239121 0.264521)
							(end -0.2032 0.2794)
						)
						(arc
							(start 0.2032 0.2794)
							(mid 0.239121 0.264521)
							(end 0.254 0.2286)
						)
						(arc
							(start 0.254 -0.2286)
							(mid 0.239121 -0.264521)
							(end 0.2032 -0.2794)
						)
					)
					(width 0)
					(fill yes)
				)
			)
		)
		(pad "2" smd custom
			(at 0 0.4318 90)
			(size 0.127 0.127)
			(layers "F.Cu" "F.Mask" "F.Paste")
			(net "SPI_CLK_GBE")
			(options
				(clearance outline)
				(anchor circle)
			)
			(primitives
				(gr_poly
					(pts
						(arc
							(start -0.2032 -0.2794)
							(mid -0.239121 -0.264521)
							(end -0.254 -0.2286)
						)
						(arc
							(start -0.254 0.2286)
							(mid -0.239121 0.264521)
							(end -0.2032 0.2794)
						)
						(arc
							(start 0.2032 0.2794)
							(mid 0.239121 0.264521)
							(end 0.254 0.2286)
						)
						(arc
							(start 0.254 -0.2286)
							(mid 0.239121 -0.264521)
							(end 0.2032 -0.2794)
						)
					)
					(width 0)
					(fill yes)
				)
			)
		)
	)
	(footprint ""
		(layer "F.Cu")
		(at 55.2958 -48.26)
		(property "Reference" "PC101"
			(at 0 0 0)
			(layer "F.SilkS")
			(hide yes)
			(effects
				(font
					(size 1.27 1.27)
				)
			)
		)
		(property "Value" "SC680P50V2KX-2GP"
			(at 1.8923 -1.2065 0)
			(unlocked yes)
			(layer "F.Fab")
			(hide yes)
			(effects
				(font
					(size 1.016 1.016)
					(thickness 0.1524)
				)
			)
		)
		(property "Device Type" "C402H22"
			(at 1.8923 -2.7305 0)
			(unlocked yes)
			(layer "F.Fab")
			(hide yes)
			(effects
				(font
					(size 1.016 1.016)
					(thickness 0.1524)
				)
			)
		)
		(duplicate_pad_numbers_are_jumpers no)
		(fp_rect
			(start -0.381 0.7366)
			(end 0.381 -0.7366)
			(stroke
				(width 0)
				(type default)
			)
			(fill no)
			(layer "F.CrtYd")
		)
		(fp_rect
			(start -0.381 0.7366)
			(end 0.381 -0.7366)
			(stroke
				(width 0)
				(type default)
			)
			(fill no)
			(layer "F.Fab")
		)
		(pad "1" smd custom
			(at 0 -0.4572)
			(size 0.1143 0.1143)
			(layers "F.Cu" "F.Mask" "F.Paste")
			(net "VR_PVIN_P1V0_STBY")
			(options
				(clearance outline)
				(anchor circle)
			)
			(primitives
				(gr_poly
					(pts
						(arc
							(start -0.254 -0.1778)
							(mid -0.239121 -0.213721)
							(end -0.2032 -0.2286)
						)
						(arc
							(start 0.2032 -0.2286)
							(mid 0.239121 -0.213721)
							(end 0.254 -0.1778)
						)
						(arc
							(start 0.254 0.1778)
							(mid 0.239121 0.213721)
							(end 0.2032 0.2286)
						)
						(arc
							(start -0.2032 0.2286)
							(mid -0.239121 0.213721)
							(end -0.254 0.1778)
						)
					)
					(width 0)
					(fill yes)
				)
			)
		)
		(pad "2" smd custom
			(at 0 0.4572)
			(size 0.1143 0.1143)
			(layers "F.Cu" "F.Mask" "F.Paste")
			(net "GND")
			(options
				(clearance outline)
				(anchor circle)
			)
			(primitives
				(gr_poly
					(pts
						(arc
							(start -0.254 -0.1778)
							(mid -0.239121 -0.213721)
							(end -0.2032 -0.2286)
						)
						(arc
							(start 0.2032 -0.2286)
							(mid 0.239121 -0.213721)
							(end 0.254 -0.1778)
						)
						(arc
							(start 0.254 0.1778)
							(mid 0.239121 0.213721)
							(end 0.2032 0.2286)
						)
						(arc
							(start -0.2032 0.2286)
							(mid -0.239121 0.213721)
							(end -0.254 0.1778)
						)
					)
					(width 0)
					(fill yes)
				)
			)
		)
	)
	(footprint ""
		(layer "F.Cu")
		(at 169.672 -53.2892 180)
		(property "Reference" "R79"
			(at 0 0 180)
			(layer "F.SilkS")
			(hide yes)
			(effects
				(font
					(size 1.27 1.27)
				)
			)
		)
		(property "Value" "1KR2F-3-GP"
			(at 0.064008 -3.993896 180)
			(unlocked yes)
			(layer "F.Fab")
			(hide yes)
			(effects
				(font
					(size 1.016 1.016)
					(thickness 0.1524)
				)
			)
		)
		(property "Device Type" "R402H16"
			(at 0.064008 -5.517896 180)
			(unlocked yes)
			(layer "F.Fab")
			(hide yes)
			(effects
				(font
					(size 1.016 1.016)
					(thickness 0.1524)
				)
			)
		)
		(duplicate_pad_numbers_are_jumpers no)
		(fp_rect
			(start -0.381 0.8382)
			(end 0.381 -0.8382)
			(stroke
				(width 0)
				(type default)
			)
			(fill no)
			(layer "F.CrtYd")
		)
		(fp_rect
			(start -0.381 0.8382)
			(end 0.381 -0.8382)
			(stroke
				(width 0)
				(type default)
			)
			(fill no)
			(layer "F.Fab")
		)
		(pad "1" smd custom
			(at 0 -0.4318 180)
			(size 0.127 0.127)
			(layers "F.Cu" "F.Mask" "F.Paste")
			(net "C_DATA0")
			(options
				(clearance outline)
				(anchor circle)
			)
			(primitives
				(gr_poly
					(pts
						(arc
							(start -0.2032 -0.2794)
							(mid -0.239121 -0.264521)
							(end -0.254 -0.2286)
						)
						(arc
							(start -0.254 0.2286)
							(mid -0.239121 0.264521)
							(end -0.2032 0.2794)
						)
						(arc
							(start 0.2032 0.2794)
							(mid 0.239121 0.264521)
							(end 0.254 0.2286)
						)
						(arc
							(start 0.254 -0.2286)
							(mid 0.239121 -0.264521)
							(end 0.2032 -0.2794)
						)
					)
					(width 0)
					(fill yes)
				)
			)
		)
		(pad "2" smd custom
			(at 0 0.4318 180)
			(size 0.127 0.127)
			(layers "F.Cu" "F.Mask" "F.Paste")
			(net "P3V3_STBY")
			(options
				(clearance outline)
				(anchor circle)
			)
			(primitives
				(gr_poly
					(pts
						(arc
							(start -0.2032 -0.2794)
							(mid -0.239121 -0.264521)
							(end -0.254 -0.2286)
						)
						(arc
							(start -0.254 0.2286)
							(mid -0.239121 0.264521)
							(end -0.2032 0.2794)
						)
						(arc
							(start 0.2032 0.2794)
							(mid 0.239121 0.264521)
							(end 0.254 0.2286)
						)
						(arc
							(start 0.254 -0.2286)
							(mid 0.239121 -0.264521)
							(end 0.2032 -0.2794)
						)
					)
					(width 0)
					(fill yes)
				)
			)
		)
	)
	(footprint ""
		(layer "F.Cu")
		(at 69.596 -55.626 90)
		(property "Reference" "R166"
			(at 0 0 90)
			(layer "F.SilkS")
			(hide yes)
			(effects
				(font
					(size 1.27 1.27)
				)
			)
		)
		(property "Value" "0R2J-2-GP"
			(at 1.7907 -1.1176 90)
			(unlocked yes)
			(layer "F.Fab")
			(hide yes)
			(effects
				(font
					(size 1.016 1.016)
					(thickness 0.1524)
				)
			)
		)
		(property "Device Type" "R402H16"
			(at 1.7907 -2.6416 90)
			(unlocked yes)
			(layer "F.Fab")
			(hide yes)
			(effects
				(font
					(size 1.016 1.016)
					(thickness 0.1524)
				)
			)
		)
		(duplicate_pad_numbers_are_jumpers no)
		(fp_rect
			(start -0.381 0.8382)
			(end 0.381 -0.8382)
			(stroke
				(width 0)
				(type default)
			)
			(fill no)
			(layer "F.CrtYd")
		)
		(fp_rect
			(start -0.381 0.8382)
			(end 0.381 -0.8382)
			(stroke
				(width 0)
				(type default)
			)
			(fill no)
			(layer "F.Fab")
		)
		(pad "1" smd custom
			(at 0 -0.4318 90)
			(size 0.127 0.127)
			(layers "F.Cu" "F.Mask" "F.Paste")
			(net "P1V8")
			(options
				(clearance outline)
				(anchor circle)
			)
			(primitives
				(gr_poly
					(pts
						(arc
							(start -0.2032 -0.2794)
							(mid -0.239121 -0.264521)
							(end -0.254 -0.2286)
						)
						(arc
							(start -0.254 0.2286)
							(mid -0.239121 0.264521)
							(end -0.2032 0.2794)
						)
						(arc
							(start 0.2032 0.2794)
							(mid 0.239121 0.264521)
							(end 0.254 0.2286)
						)
						(arc
							(start 0.254 -0.2286)
							(mid 0.239121 -0.264521)
							(end 0.2032 -0.2794)
						)
					)
					(width 0)
					(fill yes)
				)
			)
		)
		(pad "2" smd custom
			(at 0 0.4318 90)
			(size 0.127 0.127)
			(layers "F.Cu" "F.Mask" "F.Paste")
			(net "P1V8_SENSE")
			(options
				(clearance outline)
				(anchor circle)
			)
			(primitives
				(gr_poly
					(pts
						(arc
							(start -0.2032 -0.2794)
							(mid -0.239121 -0.264521)
							(end -0.254 -0.2286)
						)
						(arc
							(start -0.254 0.2286)
							(mid -0.239121 0.264521)
							(end -0.2032 0.2794)
						)
						(arc
							(start 0.2032 0.2794)
							(mid 0.239121 0.264521)
							(end 0.254 0.2286)
						)
						(arc
							(start 0.254 -0.2286)
							(mid 0.239121 -0.264521)
							(end 0.2032 -0.2794)
						)
					)
					(width 0)
					(fill yes)
				)
			)
		)
	)
)
